(kicad_pcb
	(version 20260206)
	(generator "pcbnew")
	(generator_version "10.0")
	(general
		(thickness 1.6)
		(legacy_teardrops no)
	)
	(paper "A4")
	(title_block
		(title "01162023_DA0F0TEBIF0_F0T_Expander_BD_F_brd_V02_OCP.brd")
		(comment 1 "Grand Teton / footprints 8008-8016 of 9728")
	)
	(layers
		(0 "F.Cu" signal "TOP")
		(4 "In1.Cu" signal "GND")
		(6 "In2.Cu" signal "VCC")
		(8 "In3.Cu" signal "VCC1")
		(10 "In4.Cu" signal "GND1")
		(12 "In5.Cu" signal "IN1")
		(14 "In6.Cu" signal "GND2")
		(16 "In7.Cu" signal "IN2")
		(18 "In8.Cu" signal "GND3")
		(20 "In9.Cu" signal "IN3")
		(22 "In10.Cu" signal "GND4")
		(24 "In11.Cu" signal "IN4")
		(26 "In12.Cu" signal "GND5")
		(28 "In13.Cu" signal "IN5")
		(30 "In14.Cu" signal "GND6")
		(32 "In15.Cu" signal "IN6")
		(34 "In16.Cu" signal "GND7")
		(2 "B.Cu" signal "BOTTOM")
		(9 "F.Adhes" user "F.Adhesive")
		(11 "B.Adhes" user "B.Adhesive")
		(13 "F.Paste" user "Package Geometry/Pastemask Top")
		(15 "B.Paste" user "Package Geometry/Pastemask Bottom")
		(5 "F.SilkS" user "Ref Des/Silkscreen Top")
		(7 "B.SilkS" user "Ref Des/Silkscreen Bottom")
		(1 "F.Mask" user "Board Geometry/Soldermask Top")
		(3 "B.Mask" user "Board Geometry/Soldermask Bottom")
		(17 "Dwgs.User" user "User.Drawings")
		(19 "Cmts.User" user "User.Comments")
		(21 "Eco1.User" user "User.Eco1")
		(23 "Eco2.User" user "User.Eco2")
		(25 "Edge.Cuts" user "Board Geometry/Outline")
		(27 "Margin" user)
		(31 "F.CrtYd" user "Package Geometry/Place Bound Top")
		(29 "B.CrtYd" user "Package Geometry/Place Bound Bottom")
		(35 "F.Fab" user "Ref Des/Assembly Top")
		(33 "B.Fab" user "Ref Des/Assembly Bottom")
	)
	(footprint ""
		(layer "B.Cu")
		(at 222.726758 -279.910032 -90)
		(property "Reference" "C4292"
			(at 0 0 90)
			(layer "B.SilkS")
			(hide yes)
			(effects
				(font
					(size 1.27 1.27)
				)
				(justify mirror)
			)
		)
		(property "Value" ""
			(at 0 0 90)
			(layer "B.Fab")
			(effects
				(font
					(size 1.27 1.27)
				)
				(justify mirror)
			)
		)
		(duplicate_pad_numbers_are_jumpers no)
		(fp_line
			(start -0.299974 0.150114)
			(end 0.299974 0.150114)
			(stroke
				(width 0.1)
				(type default)
			)
			(layer "B.Fab")
		)
		(fp_line
			(start 0.299974 0.150114)
			(end 0.299974 -0.150114)
			(stroke
				(width 0.1)
				(type default)
			)
			(layer "B.Fab")
		)
		(fp_line
			(start -0.299974 -0.150114)
			(end -0.299974 0.150114)
			(stroke
				(width 0.1)
				(type default)
			)
			(layer "B.Fab")
		)
		(fp_line
			(start 0.299974 -0.150114)
			(end -0.299974 -0.150114)
			(stroke
				(width 0.1)
				(type default)
			)
			(layer "B.Fab")
		)
		(pad "1" smd rect
			(at 0.2667 0 90)
			(size 0.3048 0.381)
			(layers "B.Cu" "B.Mask" "B.Paste")
			(net "P1V25_PEX1")
		)
		(pad "2" smd rect
			(at -0.2667 0 90)
			(size 0.3048 0.381)
			(layers "B.Cu" "B.Mask" "B.Paste")
			(net "GND")
		)
	)
	(footprint ""
		(layer "B.Cu")
		(at 388.473696 -295.79824 180)
		(property "Reference" "R3494"
			(at 0 0 0)
			(layer "B.SilkS")
			(hide yes)
			(effects
				(font
					(size 1.27 1.27)
				)
				(justify mirror)
			)
		)
		(property "Value" ""
			(at 0 0 0)
			(layer "B.Fab")
			(effects
				(font
					(size 1.27 1.27)
				)
				(justify mirror)
			)
		)
		(duplicate_pad_numbers_are_jumpers no)
		(fp_line
			(start 0.7874 0.4064)
			(end 0.7874 -0.4064)
			(stroke
				(width 0.1524)
				(type default)
			)
			(layer "B.SilkS")
		)
		(fp_line
			(start 0.7874 -0.4064)
			(end -0.7874 -0.4064)
			(stroke
				(width 0.1524)
				(type default)
			)
			(layer "B.SilkS")
		)
		(fp_line
			(start -0.7874 0.4064)
			(end 0.7874 0.4064)
			(stroke
				(width 0.1524)
				(type default)
			)
			(layer "B.SilkS")
		)
		(fp_line
			(start -0.7874 -0.4064)
			(end -0.7874 0.4064)
			(stroke
				(width 0.1524)
				(type default)
			)
			(layer "B.SilkS")
		)
		(fp_line
			(start 0.67945 0.3048)
			(end 0.67945 -0.305054)
			(stroke
				(width 0.1)
				(type default)
			)
			(layer "B.Fab")
		)
		(fp_line
			(start 0.67945 -0.305054)
			(end 0.12065 -0.305054)
			(stroke
				(width 0.1)
				(type default)
			)
			(layer "B.Fab")
		)
		(fp_line
			(start 0.12065 0.3048)
			(end 0.67945 0.3048)
			(stroke
				(width 0.1)
				(type default)
			)
			(layer "B.Fab")
		)
		(fp_line
			(start 0.12065 0.2794)
			(end 0.12065 0.3048)
			(stroke
				(width 0.1)
				(type default)
			)
			(layer "B.Fab")
		)
		(fp_line
			(start 0.12065 -0.2794)
			(end -0.12065 -0.2794)
			(stroke
				(width 0.1)
				(type default)
			)
			(layer "B.Fab")
		)
		(fp_line
			(start 0.12065 -0.305054)
			(end 0.12065 -0.2794)
			(stroke
				(width 0.1)
				(type default)
			)
			(layer "B.Fab")
		)
		(fp_line
			(start -0.120396 0.3048)
			(end -0.120396 0.2794)
			(stroke
				(width 0.1)
				(type default)
			)
			(layer "B.Fab")
		)
		(fp_line
			(start -0.120396 0.2794)
			(end 0.12065 0.2794)
			(stroke
				(width 0.1)
				(type default)
			)
			(layer "B.Fab")
		)
		(fp_line
			(start -0.12065 -0.2794)
			(end -0.12065 -0.3048)
			(stroke
				(width 0.1)
				(type default)
			)
			(layer "B.Fab")
		)
		(fp_line
			(start -0.12065 -0.3048)
			(end -0.67945 -0.3048)
			(stroke
				(width 0.1)
				(type default)
			)
			(layer "B.Fab")
		)
		(fp_line
			(start -0.67945 0.3048)
			(end -0.120396 0.3048)
			(stroke
				(width 0.1)
				(type default)
			)
			(layer "B.Fab")
		)
		(fp_line
			(start -0.67945 -0.3048)
			(end -0.67945 0.3048)
			(stroke
				(width 0.1)
				(type default)
			)
			(layer "B.Fab")
		)
		(pad "1" smd circle
			(at 0.40005 0)
			(size 0 0)
			(layers "B.Cu" "B.Mask" "B.Paste")
			(net "SPI_PEX3_SDIO0_R")
		)
		(pad "2" smd circle
			(at -0.40005 0)
			(size 0 0)
			(layers "B.Cu" "B.Mask" "B.Paste")
			(net "SPI_PEX3_SDIO0")
		)
	)
	(footprint ""
		(layer "B.Cu")
		(at 63.924942 -286.399732 90)
		(property "Reference" "C2968"
			(at 0 0 90)
			(layer "B.SilkS")
			(hide yes)
			(effects
				(font
					(size 1.27 1.27)
				)
				(justify mirror)
			)
		)
		(property "Value" ""
			(at 0 0 90)
			(layer "B.Fab")
			(effects
				(font
					(size 1.27 1.27)
				)
				(justify mirror)
			)
		)
		(duplicate_pad_numbers_are_jumpers no)
		(fp_line
			(start 0.299974 -0.150114)
			(end -0.299974 -0.150114)
			(stroke
				(width 0.1)
				(type default)
			)
			(layer "B.Fab")
		)
		(fp_line
			(start -0.299974 -0.150114)
			(end -0.299974 0.150114)
			(stroke
				(width 0.1)
				(type default)
			)
			(layer "B.Fab")
		)
		(fp_line
			(start 0.299974 0.150114)
			(end 0.299974 -0.150114)
			(stroke
				(width 0.1)
				(type default)
			)
			(layer "B.Fab")
		)
		(fp_line
			(start -0.299974 0.150114)
			(end 0.299974 0.150114)
			(stroke
				(width 0.1)
				(type default)
			)
			(layer "B.Fab")
		)
		(pad "1" smd rect
			(at 0.2667 0 270)
			(size 0.3048 0.381)
			(layers "B.Cu" "B.Mask" "B.Paste")
			(net "P1V25_SERDES_VDDPLL_PEX0")
		)
		(pad "2" smd rect
			(at -0.2667 0 270)
			(size 0.3048 0.381)
			(layers "B.Cu" "B.Mask" "B.Paste")
			(net "GND")
		)
	)
	(footprint ""
		(layer "B.Cu")
		(at 279.977342 -300.7995 -90)
		(property "Reference" "C3370"
			(at 0 0 90)
			(layer "B.SilkS")
			(hide yes)
			(effects
				(font
					(size 1.27 1.27)
				)
				(justify mirror)
			)
		)
		(property "Value" ""
			(at 0 0 90)
			(layer "B.Fab")
			(effects
				(font
					(size 1.27 1.27)
				)
				(justify mirror)
			)
		)
		(duplicate_pad_numbers_are_jumpers no)
		(fp_line
			(start -0.299974 0.150114)
			(end 0.299974 0.150114)
			(stroke
				(width 0.1)
				(type default)
			)
			(layer "B.Fab")
		)
		(fp_line
			(start 0.299974 0.150114)
			(end 0.299974 -0.150114)
			(stroke
				(width 0.1)
				(type default)
			)
			(layer "B.Fab")
		)
		(fp_line
			(start -0.299974 -0.150114)
			(end -0.299974 0.150114)
			(stroke
				(width 0.1)
				(type default)
			)
			(layer "B.Fab")
		)
		(fp_line
			(start 0.299974 -0.150114)
			(end -0.299974 -0.150114)
			(stroke
				(width 0.1)
				(type default)
			)
			(layer "B.Fab")
		)
		(pad "1" smd rect
			(at 0.2667 0 90)
			(size 0.3048 0.381)
			(layers "B.Cu" "B.Mask" "B.Paste")
			(net "PCEPLL0_VDDA18_PEX2")
		)
		(pad "2" smd rect
			(at -0.2667 0 90)
			(size 0.3048 0.381)
			(layers "B.Cu" "B.Mask" "B.Paste")
			(net "GND")
		)
	)
	(footprint ""
		(layer "B.Cu")
		(at 217.665808 -276.672294)
		(property "Reference" "C4275"
			(at 0 0 0)
			(layer "B.SilkS")
			(hide yes)
			(effects
				(font
					(size 1.27 1.27)
				)
				(justify mirror)
			)
		)
		(property "Value" ""
			(at 0 0 0)
			(layer "B.Fab")
			(effects
				(font
					(size 1.27 1.27)
				)
				(justify mirror)
			)
		)
		(duplicate_pad_numbers_are_jumpers no)
		(fp_line
			(start -1.2954 -0.5842)
			(end -1.2954 0.5842)
			(stroke
				(width 0.1524)
				(type default)
			)
			(layer "B.SilkS")
		)
		(fp_line
			(start -1.2954 0.5842)
			(end 1.2954 0.5842)
			(stroke
				(width 0.1524)
				(type default)
			)
			(layer "B.SilkS")
		)
		(fp_line
			(start 1.2954 -0.5842)
			(end -1.2954 -0.5842)
			(stroke
				(width 0.1524)
				(type default)
			)
			(layer "B.SilkS")
		)
		(fp_line
			(start 1.2954 0.5842)
			(end 1.2954 -0.5842)
			(stroke
				(width 0.1524)
				(type default)
			)
			(layer "B.SilkS")
		)
		(fp_line
			(start -1.1938 -0.4064)
			(end -1.1938 0.4064)
			(stroke
				(width 0.1)
				(type default)
			)
			(layer "B.Fab")
		)
		(fp_line
			(start -1.1938 0.4064)
			(end -0.8636 0.4064)
			(stroke
				(width 0.1)
				(type default)
			)
			(layer "B.Fab")
		)
		(fp_line
			(start -0.8636 -0.4572)
			(end -0.8636 -0.4064)
			(stroke
				(width 0.1)
				(type default)
			)
			(layer "B.Fab")
		)
		(fp_line
			(start -0.8636 -0.4064)
			(end -1.1938 -0.4064)
			(stroke
				(width 0.1)
				(type default)
			)
			(layer "B.Fab")
		)
		(fp_line
			(start -0.8636 0.4064)
			(end -0.8636 0.4572)
			(stroke
				(width 0.1)
				(type default)
			)
			(layer "B.Fab")
		)
		(fp_line
			(start -0.8636 0.4572)
			(end 0.8636 0.4572)
			(stroke
				(width 0.1)
				(type default)
			)
			(layer "B.Fab")
		)
		(fp_line
			(start 0.8636 -0.4572)
			(end -0.8636 -0.4572)
			(stroke
				(width 0.1)
				(type default)
			)
			(layer "B.Fab")
		)
		(fp_line
			(start 0.8636 -0.4064)
			(end 0.8636 -0.4572)
			(stroke
				(width 0.1)
				(type default)
			)
			(layer "B.Fab")
		)
		(fp_line
			(start 0.8636 0.4064)
			(end 1.1938 0.4064)
			(stroke
				(width 0.1)
				(type default)
			)
			(layer "B.Fab")
		)
		(fp_line
			(start 0.8636 0.4572)
			(end 0.8636 0.4064)
			(stroke
				(width 0.1)
				(type default)
			)
			(layer "B.Fab")
		)
		(fp_line
			(start 1.1938 -0.4064)
			(end 0.8636 -0.4064)
			(stroke
				(width 0.1)
				(type default)
			)
			(layer "B.Fab")
		)
		(fp_line
			(start 1.1938 0.4064)
			(end 1.1938 -0.4064)
			(stroke
				(width 0.1)
				(type default)
			)
			(layer "B.Fab")
		)
		(pad "1" smd rect
			(at 0.7366 0 270)
			(size 0.7112 0.8128)
			(layers "B.Cu" "B.Mask" "B.Paste")
			(net "P1V25_PEX1")
		)
		(pad "2" smd rect
			(at -0.7366 0 270)
			(size 0.7112 0.8128)
			(layers "B.Cu" "B.Mask" "B.Paste")
			(net "GND")
		)
	)
	(footprint ""
		(layer "B.Cu")
		(at 22.507702 -173.1772 180)
		(property "Reference" "R4429"
			(at 0 0 0)
			(layer "B.SilkS")
			(hide yes)
			(effects
				(font
					(size 1.27 1.27)
				)
				(justify mirror)
			)
		)
		(property "Value" ""
			(at 0 0 0)
			(layer "B.Fab")
			(effects
				(font
					(size 1.27 1.27)
				)
				(justify mirror)
			)
		)
		(duplicate_pad_numbers_are_jumpers no)
		(fp_line
			(start 0.7874 0.4064)
			(end 0.7874 -0.4064)
			(stroke
				(width 0.1524)
				(type default)
			)
			(layer "B.SilkS")
		)
		(fp_line
			(start 0.7874 -0.4064)
			(end -0.7874 -0.4064)
			(stroke
				(width 0.1524)
				(type default)
			)
			(layer "B.SilkS")
		)
		(fp_line
			(start -0.7874 0.4064)
			(end 0.7874 0.4064)
			(stroke
				(width 0.1524)
				(type default)
			)
			(layer "B.SilkS")
		)
		(fp_line
			(start -0.7874 -0.4064)
			(end -0.7874 0.4064)
			(stroke
				(width 0.1524)
				(type default)
			)
			(layer "B.SilkS")
		)
		(fp_line
			(start 0.67945 0.3048)
			(end 0.67945 -0.305054)
			(stroke
				(width 0.1)
				(type default)
			)
			(layer "B.Fab")
		)
		(fp_line
			(start 0.67945 -0.305054)
			(end 0.12065 -0.305054)
			(stroke
				(width 0.1)
				(type default)
			)
			(layer "B.Fab")
		)
		(fp_line
			(start 0.12065 0.3048)
			(end 0.67945 0.3048)
			(stroke
				(width 0.1)
				(type default)
			)
			(layer "B.Fab")
		)
		(fp_line
			(start 0.12065 0.2794)
			(end 0.12065 0.3048)
			(stroke
				(width 0.1)
				(type default)
			)
			(layer "B.Fab")
		)
		(fp_line
			(start 0.12065 -0.2794)
			(end -0.12065 -0.2794)
			(stroke
				(width 0.1)
				(type default)
			)
			(layer "B.Fab")
		)
		(fp_line
			(start 0.12065 -0.305054)
			(end 0.12065 -0.2794)
			(stroke
				(width 0.1)
				(type default)
			)
			(layer "B.Fab")
		)
		(fp_line
			(start -0.120396 0.3048)
			(end -0.120396 0.2794)
			(stroke
				(width 0.1)
				(type default)
			)
			(layer "B.Fab")
		)
		(fp_line
			(start -0.120396 0.2794)
			(end 0.12065 0.2794)
			(stroke
				(width 0.1)
				(type default)
			)
			(layer "B.Fab")
		)
		(fp_line
			(start -0.12065 -0.2794)
			(end -0.12065 -0.3048)
			(stroke
				(width 0.1)
				(type default)
			)
			(layer "B.Fab")
		)
		(fp_line
			(start -0.12065 -0.3048)
			(end -0.67945 -0.3048)
			(stroke
				(width 0.1)
				(type default)
			)
			(layer "B.Fab")
		)
		(fp_line
			(start -0.67945 0.3048)
			(end -0.120396 0.3048)
			(stroke
				(width 0.1)
				(type default)
			)
			(layer "B.Fab")
		)
		(fp_line
			(start -0.67945 -0.3048)
			(end -0.67945 0.3048)
			(stroke
				(width 0.1)
				(type default)
			)
			(layer "B.Fab")
		)
		(pad "1" smd circle
			(at 0.40005 0)
			(size 0 0)
			(layers "B.Cu" "B.Mask" "B.Paste")
			(net "PWRGD_P5V_AUX")
		)
		(pad "2" smd circle
			(at -0.40005 0)
			(size 0 0)
			(layers "B.Cu" "B.Mask" "B.Paste")
			(net "PWRGD_P5V_AUX_R")
		)
	)
	(footprint ""
		(layer "B.Cu")
		(at 409.849828 -288.299906 90)
		(property "Reference" "C3447"
			(at 0 0 90)
			(layer "B.SilkS")
			(hide yes)
			(effects
				(font
					(size 1.27 1.27)
				)
				(justify mirror)
			)
		)
		(property "Value" ""
			(at 0 0 90)
			(layer "B.Fab")
			(effects
				(font
					(size 1.27 1.27)
				)
				(justify mirror)
			)
		)
		(duplicate_pad_numbers_are_jumpers no)
		(fp_line
			(start 0.299974 -0.150114)
			(end -0.299974 -0.150114)
			(stroke
				(width 0.1)
				(type default)
			)
			(layer "B.Fab")
		)
		(fp_line
			(start -0.299974 -0.150114)
			(end -0.299974 0.150114)
			(stroke
				(width 0.1)
				(type default)
			)
			(layer "B.Fab")
		)
		(fp_line
			(start 0.299974 0.150114)
			(end 0.299974 -0.150114)
			(stroke
				(width 0.1)
				(type default)
			)
			(layer "B.Fab")
		)
		(fp_line
			(start -0.299974 0.150114)
			(end 0.299974 0.150114)
			(stroke
				(width 0.1)
				(type default)
			)
			(layer "B.Fab")
		)
		(pad "1" smd rect
			(at 0.2667 0 270)
			(size 0.3048 0.381)
			(layers "B.Cu" "B.Mask" "B.Paste")
			(net "P1V25_PEX3")
		)
		(pad "2" smd rect
			(at -0.2667 0 270)
			(size 0.3048 0.381)
			(layers "B.Cu" "B.Mask" "B.Paste")
			(net "GND")
		)
	)
	(footprint ""
		(layer "B.Cu")
		(at 278.326342 -139.8016 180)
		(property "Reference" "C914"
			(at 0 0 0)
			(layer "B.SilkS")
			(hide yes)
			(effects
				(font
					(size 1.27 1.27)
				)
				(justify mirror)
			)
		)
		(property "Value" ""
			(at 0 0 0)
			(layer "B.Fab")
			(effects
				(font
					(size 1.27 1.27)
				)
				(justify mirror)
			)
		)
		(duplicate_pad_numbers_are_jumpers no)
		(fp_line
			(start 0.7874 0.4064)
			(end 0.7874 -0.4064)
			(stroke
				(width 0.1524)
				(type default)
			)
			(layer "B.SilkS")
		)
		(fp_line
			(start 0.7874 -0.4064)
			(end -0.7874 -0.4064)
			(stroke
				(width 0.1524)
				(type default)
			)
			(layer "B.SilkS")
		)
		(fp_line
			(start -0.7874 0.4064)
			(end 0.7874 0.4064)
			(stroke
				(width 0.1524)
				(type default)
			)
			(layer "B.SilkS")
		)
		(fp_line
			(start -0.7874 -0.4064)
			(end -0.7874 0.4064)
			(stroke
				(width 0.1524)
				(type default)
			)
			(layer "B.SilkS")
		)
		(fp_line
			(start 0.67945 0.3048)
			(end 0.67945 -0.305054)
			(stroke
				(width 0.1)
				(type default)
			)
			(layer "B.Fab")
		)
		(fp_line
			(start 0.67945 -0.305054)
			(end 0.12065 -0.305054)
			(stroke
				(width 0.1)
				(type default)
			)
			(layer "B.Fab")
		)
		(fp_line
			(start 0.12065 0.3048)
			(end 0.67945 0.3048)
			(stroke
				(width 0.1)
				(type default)
			)
			(layer "B.Fab")
		)
		(fp_line
			(start 0.12065 0.2794)
			(end 0.12065 0.3048)
			(stroke
				(width 0.1)
				(type default)
			)
			(layer "B.Fab")
		)
		(fp_line
			(start 0.12065 -0.2794)
			(end -0.12065 -0.2794)
			(stroke
				(width 0.1)
				(type default)
			)
			(layer "B.Fab")
		)
		(fp_line
			(start 0.12065 -0.305054)
			(end 0.12065 -0.2794)
			(stroke
				(width 0.1)
				(type default)
			)
			(layer "B.Fab")
		)
		(fp_line
			(start -0.120396 0.3048)
			(end -0.120396 0.2794)
			(stroke
				(width 0.1)
				(type default)
			)
			(layer "B.Fab")
		)
		(fp_line
			(start -0.120396 0.2794)
			(end 0.12065 0.2794)
			(stroke
				(width 0.1)
				(type default)
			)
			(layer "B.Fab")
		)
		(fp_line
			(start -0.12065 -0.2794)
			(end -0.12065 -0.3048)
			(stroke
				(width 0.1)
				(type default)
			)
			(layer "B.Fab")
		)
		(fp_line
			(start -0.12065 -0.3048)
			(end -0.67945 -0.3048)
			(stroke
				(width 0.1)
				(type default)
			)
			(layer "B.Fab")
		)
		(fp_line
			(start -0.67945 0.3048)
			(end -0.120396 0.3048)
			(stroke
				(width 0.1)
				(type default)
			)
			(layer "B.Fab")
		)
		(fp_line
			(start -0.67945 -0.3048)
			(end -0.67945 0.3048)
			(stroke
				(width 0.1)
				(type default)
			)
			(layer "B.Fab")
		)
		(pad "1" smd circle
			(at 0.40005 0)
			(size 0 0)
			(layers "B.Cu" "B.Mask" "B.Paste")
			(net "P3V3_NIC4")
		)
		(pad "2" smd circle
			(at -0.40005 0)
			(size 0 0)
			(layers "B.Cu" "B.Mask" "B.Paste")
			(net "GND")
		)
	)
	(footprint ""
		(layer "B.Cu")
		(at 408.899868 -299.699934 -90)
		(property "Reference" "C1943"
			(at 0 0 90)
			(layer "B.SilkS")
			(hide yes)
			(effects
				(font
					(size 1.27 1.27)
				)
				(justify mirror)
			)
		)
		(property "Value" ""
			(at 0 0 90)
			(layer "B.Fab")
			(effects
				(font
					(size 1.27 1.27)
				)
				(justify mirror)
			)
		)
		(duplicate_pad_numbers_are_jumpers no)
		(fp_line
			(start -0.299974 0.150114)
			(end 0.299974 0.150114)
			(stroke
				(width 0.1)
				(type default)
			)
			(layer "B.Fab")
		)
		(fp_line
			(start 0.299974 0.150114)
			(end 0.299974 -0.150114)
			(stroke
				(width 0.1)
				(type default)
			)
			(layer "B.Fab")
		)
		(fp_line
			(start -0.299974 -0.150114)
			(end -0.299974 0.150114)
			(stroke
				(width 0.1)
				(type default)
			)
			(layer "B.Fab")
		)
		(fp_line
			(start 0.299974 -0.150114)
			(end -0.299974 -0.150114)
			(stroke
				(width 0.1)
				(type default)
			)
			(layer "B.Fab")
		)
		(pad "1" smd rect
			(at 0.2667 0 90)
			(size 0.3048 0.381)
			(layers "B.Cu" "B.Mask" "B.Paste")
			(net "P0V8_SERDES_VDDA_PEX3")
		)
		(pad "2" smd rect
			(at -0.2667 0 90)
			(size 0.3048 0.381)
			(layers "B.Cu" "B.Mask" "B.Paste")
			(net "GND")
		)
	)
)
